# T6G (Grand Teton) — schematic netlist excerpt (pin names and nets, part order shuffled) for the footprints in the layout excerpt that follows; sources: Cadence DE-HDL packaged netlist, KiCad conversion of 04192023_DAF0TMB3IC0_F0TG_MB_C_brd_V02_OCP.brd

C2394  Q_CAP  22UF 4V 20% X6S  pkg C0402  page 73 : A = PVDDCR_CPU1_P1 ; B = GND
R472  Q_RES  33 5% EMPTY  pkg 0402LF  page 29 : A = ESPI_CPU0_ALERT_P0_N ; B = ESPI_CPU0_R_ALERT_N

(kicad_pcb
	(version 20260206)
	(generator "pcbnew")
	(generator_version "10.0")
	(general
		(thickness 1.6)
		(legacy_teardrops no)
	)
	(paper "A4")
	(title_block
		(title "04192023_DAF0TMB3IC0_F0TG_MB_C_brd_V02_OCP.brd")
		(comment 1 "Grand Teton / footprints 7072-7073 of 8354")
	)
	(layers
		(0 "F.Cu" signal "TOP")
		(4 "In1.Cu" signal "GND")
		(6 "In2.Cu" signal "IN1")
		(8 "In3.Cu" signal "GND1")
		(10 "In4.Cu" signal "IN2")
		(12 "In5.Cu" signal "GND2")
		(14 "In6.Cu" signal "IN3")
		(16 "In7.Cu" signal "GND3")
		(18 "In8.Cu" signal "VCC")
		(20 "In9.Cu" signal "VCC1")
		(22 "In10.Cu" signal "GND4")
		(24 "In11.Cu" signal "IN4")
		(26 "In12.Cu" signal "GND5")
		(28 "In13.Cu" signal "IN5")
		(30 "In14.Cu" signal "GND6")
		(32 "In15.Cu" signal "IN6")
		(34 "In16.Cu" signal "GND7")
		(2 "B.Cu" signal "BOTTOM")
		(9 "F.Adhes" user "F.Adhesive")
		(11 "B.Adhes" user "B.Adhesive")
		(13 "F.Paste" user "Package Geometry/Pastemask Top")
		(15 "B.Paste" user "Package Geometry/Pastemask Bottom")
		(5 "F.SilkS" user "Ref Des/Silkscreen Top")
		(7 "B.SilkS" user "Ref Des/Silkscreen Bottom")
		(1 "F.Mask" user "Board Geometry/Soldermask Top")
		(3 "B.Mask" user "Board Geometry/Soldermask Bottom")
		(17 "Dwgs.User" user "User.Drawings")
		(19 "Cmts.User" user "User.Comments")
		(21 "Eco1.User" user "User.Eco1")
		(23 "Eco2.User" user "User.Eco2")
		(25 "Edge.Cuts" user "Board Geometry/Outline")
		(27 "Margin" user)
		(31 "F.CrtYd" user "Package Geometry/Place Bound Top")
		(29 "B.CrtYd" user "Package Geometry/Place Bound Bottom")
		(35 "F.Fab" user "Ref Des/Assembly Top")
		(33 "B.Fab" user "Ref Des/Assembly Bottom")
	)
	(footprint ""
		(layer "B.Cu")
		(at 403.315678 -323.892672)
		(property "Reference" "R472"
			(at 0 0 0)
			(layer "B.SilkS")
			(hide yes)
			(effects
				(font
					(size 1.27 1.27)
				)
				(justify mirror)
			)
		)
		(property "Value" ""
			(at 0 0 0)
			(layer "B.Fab")
			(effects
				(font
					(size 1.27 1.27)
				)
				(justify mirror)
			)
		)
		(duplicate_pad_numbers_are_jumpers no)
		(fp_line
			(start -0.7874 -0.4064)
			(end -0.7874 0.4064)
			(stroke
				(width 0.1524)
				(type default)
			)
			(layer "B.SilkS")
		)
		(fp_line
			(start -0.7874 0.4064)
			(end 0.7874 0.4064)
			(stroke
				(width 0.1524)
				(type default)
			)
			(layer "B.SilkS")
		)
		(fp_line
			(start 0.7874 -0.4064)
			(end -0.7874 -0.4064)
			(stroke
				(width 0.1524)
				(type default)
			)
			(layer "B.SilkS")
		)
		(fp_line
			(start 0.7874 0.4064)
			(end 0.7874 -0.4064)
			(stroke
				(width 0.1524)
				(type default)
			)
			(layer "B.SilkS")
		)
		(fp_line
			(start -0.67945 -0.3048)
			(end -0.67945 0.3048)
			(stroke
				(width 0.1)
				(type default)
			)
			(layer "B.Fab")
		)
		(fp_line
			(start -0.67945 0.3048)
			(end -0.120396 0.3048)
			(stroke
				(width 0.1)
				(type default)
			)
			(layer "B.Fab")
		)
		(fp_line
			(start -0.12065 -0.3048)
			(end -0.67945 -0.3048)
			(stroke
				(width 0.1)
				(type default)
			)
			(layer "B.Fab")
		)
		(fp_line
			(start -0.12065 -0.2794)
			(end -0.12065 -0.3048)
			(stroke
				(width 0.1)
				(type default)
			)
			(layer "B.Fab")
		)
		(fp_line
			(start -0.120396 0.2794)
			(end 0.12065 0.2794)
			(stroke
				(width 0.1)
				(type default)
			)
			(layer "B.Fab")
		)
		(fp_line
			(start -0.120396 0.3048)
			(end -0.120396 0.2794)
			(stroke
				(width 0.1)
				(type default)
			)
			(layer "B.Fab")
		)
		(fp_line
			(start 0.12065 -0.305054)
			(end 0.12065 -0.2794)
			(stroke
				(width 0.1)
				(type default)
			)
			(layer "B.Fab")
		)
		(fp_line
			(start 0.12065 -0.2794)
			(end -0.12065 -0.2794)
			(stroke
				(width 0.1)
				(type default)
			)
			(layer "B.Fab")
		)
		(fp_line
			(start 0.12065 0.2794)
			(end 0.12065 0.3048)
			(stroke
				(width 0.1)
				(type default)
			)
			(layer "B.Fab")
		)
		(fp_line
			(start 0.12065 0.3048)
			(end 0.67945 0.3048)
			(stroke
				(width 0.1)
				(type default)
			)
			(layer "B.Fab")
		)
		(fp_line
			(start 0.67945 -0.305054)
			(end 0.12065 -0.305054)
			(stroke
				(width 0.1)
				(type default)
			)
			(layer "B.Fab")
		)
		(fp_line
			(start 0.67945 0.3048)
			(end 0.67945 -0.305054)
			(stroke
				(width 0.1)
				(type default)
			)
			(layer "B.Fab")
		)
		(pad "1" smd rect
			(at 0.40005 0)
			(size 0.4572 0.508)
			(layers "B.Cu" "B.Mask" "B.Paste")
			(net "ESPI_CPU0_ALERT_P0_N")
		)
		(pad "2" smd rect
			(at -0.40005 0)
			(size 0.4572 0.508)
			(layers "B.Cu" "B.Mask" "B.Paste")
			(net "ESPI_CPU0_R_ALERT_N")
		)
	)
	(footprint ""
		(layer "B.Cu")
		(at 104.561386 -267.529564)
		(property "Reference" "C2394"
			(at 0 0 0)
			(layer "B.SilkS")
			(hide yes)
			(effects
				(font
					(size 1.27 1.27)
				)
				(justify mirror)
			)
		)
		(property "Value" ""
			(at 0 0 0)
			(layer "B.Fab")
			(effects
				(font
					(size 1.27 1.27)
				)
				(justify mirror)
			)
		)
		(duplicate_pad_numbers_are_jumpers no)
		(fp_line
			(start -0.7874 -0.4064)
			(end -0.7874 0.4064)
			(stroke
				(width 0.1524)
				(type default)
			)
			(layer "B.SilkS")
		)
		(fp_line
			(start -0.7874 0.4064)
			(end 0.7874 0.4064)
			(stroke
				(width 0.1524)
				(type default)
			)
			(layer "B.SilkS")
		)
		(fp_line
			(start 0.7874 -0.4064)
			(end -0.7874 -0.4064)
			(stroke
				(width 0.1524)
				(type default)
			)
			(layer "B.SilkS")
		)
		(fp_line
			(start 0.7874 0.4064)
			(end 0.7874 -0.4064)
			(stroke
				(width 0.1524)
				(type default)
			)
			(layer "B.SilkS")
		)
		(fp_line
			(start -0.67945 -0.3048)
			(end -0.67945 0.3048)
			(stroke
				(width 0.1)
				(type default)
			)
			(layer "B.Fab")
		)
		(fp_line
			(start -0.67945 0.3048)
			(end -0.120396 0.3048)
			(stroke
				(width 0.1)
				(type default)
			)
			(layer "B.Fab")
		)
		(fp_line
			(start -0.12065 -0.3048)
			(end -0.67945 -0.3048)
			(stroke
				(width 0.1)
				(type default)
			)
			(layer "B.Fab")
		)
		(fp_line
			(start -0.12065 -0.2794)
			(end -0.12065 -0.3048)
			(stroke
				(width 0.1)
				(type default)
			)
			(layer "B.Fab")
		)
		(fp_line
			(start -0.120396 0.2794)
			(end 0.12065 0.2794)
			(stroke
				(width 0.1)
				(type default)
			)
			(layer "B.Fab")
		)
		(fp_line
			(start -0.120396 0.3048)
			(end -0.120396 0.2794)
			(stroke
				(width 0.1)
				(type default)
			)
			(layer "B.Fab")
		)
		(fp_line
			(start 0.12065 -0.305054)
			(end 0.12065 -0.2794)
			(stroke
				(width 0.1)
				(type default)
			)
			(layer "B.Fab")
		)
		(fp_line
			(start 0.12065 -0.2794)
			(end -0.12065 -0.2794)
			(stroke
				(width 0.1)
				(type default)
			)
			(layer "B.Fab")
		)
		(fp_line
			(start 0.12065 0.2794)
			(end 0.12065 0.3048)
			(stroke
				(width 0.1)
				(type default)
			)
			(layer "B.Fab")
		)
		(fp_line
			(start 0.12065 0.3048)
			(end 0.67945 0.3048)
			(stroke
				(width 0.1)
				(type default)
			)
			(layer "B.Fab")
		)
		(fp_line
			(start 0.67945 -0.305054)
			(end 0.12065 -0.305054)
			(stroke
				(width 0.1)
				(type default)
			)
			(layer "B.Fab")
		)
		(fp_line
			(start 0.67945 0.3048)
			(end 0.67945 -0.305054)
			(stroke
				(width 0.1)
				(type default)
			)
			(layer "B.Fab")
		)
		(pad "1" smd circle
			(at 0.40005 0 180)
			(size 0 0)
			(layers "B.Cu" "B.Mask" "B.Paste")
			(net "PVDDCR_CPU1_P1")
		)
		(pad "2" smd circle
			(at -0.40005 0 180)
			(size 0 0)
			(layers "B.Cu" "B.Mask" "B.Paste")
			(net "GND")
		)
	)
)
